#ISCELL
  logical_power design_note *
  *
#ISCELL
  mstr_misc dns *
  *
#ISCELL
  pure_quanta quanta_title_block_c *
  *
#ISCELL
  standard offpage *
  page14_i1
#CELL
  pure_quanta ast2600a3gp *
  page14_i149
#ISCELL
  logical_power universal_gnd *
  page14_i162
#CELL
  pure_quanta q_res *
  page14_i163
#CELL
  pure_quanta q_res *
  page14_i164
#CELL
  pure_quanta q_res *
  page14_i165
#CELL
  pure_quanta q_res *
  page14_i166
#ISCELL
  standard offpage *
  page14_i167
#ISCELL
  standard offpage *
  page14_i168
#CELL
  pure_quanta q_res *
  page14_i171
#CELL
  pure_quanta q_res *
  page14_i172
#CELL
  pure_quanta q_res *
  page14_i173
#CELL
  pure_quanta q_res *
  page14_i174
#CELL
  pure_quanta q_res *
  page14_i183
#ISCELL
  standard offpage *
  page14_i184
#ISCELL
  standard offpage *
  page14_i185
#ISCELL
  standard offpage *
  page14_i186
#ISCELL
  standard offpage *
  page14_i187
#CELL
  pure_quanta q_res *
  page14_i188
#CELL
  pure_quanta q_res *
  page14_i189
#CELL
  pure_quanta q_res *
  page14_i190
#ISCELL
  standard offpage *
  page14_i2
#ISCELL
  logical_power universal_gnd *
  page14_i208
#ISCELL
  standard offpage *
  page14_i21
#ISCELL
  logical_power universal_power *
  page14_i218
#ISCELL
  logical_power universal_power *
  page14_i219
#ISCELL
  standard offpage *
  page14_i22
#CELL
  pure_quanta q_res *
  page14_i220
#CELL
  pure_quanta q_res *
  page14_i221
#CELL
  pure_quanta q_res *
  page14_i222
#CELL
  pure_quanta q_res *
  page14_i223
#CELL
  pure_quanta q_res *
  page14_i224
#CELL
  pure_quanta q_res *
  page14_i225
#ISCELL
  standard offpage *
  page14_i228
#CELL
  pure_quanta q_res *
  page14_i229
#ISCELL
  logical_power universal_power *
  page14_i230
#CELL
  pure_quanta q_res *
  page14_i231
#CELL
  pure_quanta q_res *
  page14_i232
#CELL
  pure_quanta q_res *
  page14_i233
#CELL
  pure_quanta q_res *
  page14_i234
#CELL
  pure_quanta q_res *
  page14_i235
#CELL
  pure_quanta q_res *
  page14_i236
#CELL
  pure_quanta q_res *
  page14_i237
#CELL
  pure_quanta q_res *
  page14_i238
#CELL
  pure_quanta q_res *
  page14_i239
#ISCELL
  standard offpage *
  page14_i3
#ISCELL
  standard offpage *
  page14_i4
#ISCELL
  standard offpage *
  page14_i45
#ISCELL
  standard offpage *
  page14_i46
#ISCELL
  standard offpage *
  page14_i47
#ISCELL
  standard offpage *
  page14_i48
#ISCELL
  standard offpage *
  page14_i87
#ISCELL
  standard offpage *
  page14_i88
#ISCELL
  logical_power universal_power *
  page14_i9
